(kicad_pcb
	(version 20260206)
	(generator "pcbnew")
	(generator_version "10.0")
	(general
		(thickness 1.6)
		(legacy_teardrops no)
	)
	(paper "A4")
	(title_block
		(title "v2-pdb — ms_pdb_v2.brd")
		(comment 1 "Open CloudServer (Microsoft) / footprint 328 of 348 (J11), pads 1-46 of 46")
	)
	(layers
		(0 "F.Cu" signal "TOP")
		(4 "In1.Cu" signal "GND")
		(6 "In2.Cu" signal "IN1")
		(8 "In3.Cu" signal "VCC")
		(10 "In4.Cu" signal "VCC1")
		(12 "In5.Cu" signal "IN2")
		(14 "In6.Cu" signal "GND1")
		(2 "B.Cu" signal "BOTTOM")
		(9 "F.Adhes" user "F.Adhesive")
		(11 "B.Adhes" user "B.Adhesive")
		(13 "F.Paste" user "Package Geometry/Pastemask Top")
		(15 "B.Paste" user "Package Geometry/Pastemask Bottom")
		(5 "F.SilkS" user "Ref Des/Silkscreen Top")
		(7 "B.SilkS" user "Ref Des/Silkscreen Bottom")
		(1 "F.Mask" user "Board Geometry/Soldermask Top")
		(3 "B.Mask" user "Board Geometry/Soldermask Bottom")
		(17 "Dwgs.User" user "User.Drawings")
		(19 "Cmts.User" user "User.Comments")
		(21 "Eco1.User" user "User.Eco1")
		(23 "Eco2.User" user "User.Eco2")
		(25 "Edge.Cuts" user "Board Geometry/Outline")
		(27 "Margin" user)
		(31 "F.CrtYd" user "Package Geometry/Place Bound Top")
		(29 "B.CrtYd" user "Package Geometry/Place Bound Bottom")
		(35 "F.Fab" user "Ref Des/Assembly Top")
		(33 "B.Fab" user "Ref Des/Assembly Bottom")
	)
	(footprint ""
		(layer "B.Cu")
		(at 44.040044 -186.06008 90)
		(property "Reference" "J11"
			(at 6.252972 -4.579366 0)
			(unlocked yes)
			(layer "B.SilkS")
			(effects
				(font
					(size 0.7874 0.5842)
					(thickness 0.1524)
				)
				(justify left mirror)
			)
		)
		(property "Value" ""
			(at 0 0 90)
			(layer "B.Fab")
			(effects
				(font
					(size 1.27 1.27)
				)
				(justify mirror)
			)
		)
		(duplicate_pad_numbers_are_jumpers no)
		(pad "" np_thru_hole circle
			(at -1.35001 -2.54)
			(size 2.5146 2.5146)
			(drill 2.5146)
			(layers "*.Cu" "*.Mask")
			(clearance 0.381)
			(thermal_gap 0.381)
		)
		(pad "" np_thru_hole circle
			(at 0 50.8)
			(size 2.5146 2.5146)
			(drill 2.5146)
			(layers "*.Cu" "*.Mask")
			(clearance 0.381)
			(thermal_gap 0.381)
		)
		(pad "P1" thru_hole rect
			(at 0 0)
			(size 1.1684 1.1684)
			(drill 0.762)
			(layers "*.Cu" "*.Mask")
			(remove_unused_layers no)
			(net "GND")
			(clearance 0.0508)
			(padstack
				(mode front_inner_back)
				(layer "Inner"
					(shape circle)
					(size 1.1684 1.1684)
					(clearance 0.0508)
				)
				(layer "B.Cu"
					(shape rect)
					(size 1.1684 1.1684)
					(thermal_gap 0.0508)
					(clearance 0.0508)
				)
			)
		)
		(pad "P2" thru_hole circle
			(at 0 2.54)
			(size 1.1684 1.1684)
			(drill 0.762)
			(layers "*.Cu" "*.Mask")
			(remove_unused_layers no)
			(net "GND")
			(clearance 0.0508)
			(thermal_gap 0.0508)
		)
		(pad "P3" thru_hole circle
			(at 0 5.08)
			(size 1.1684 1.1684)
			(drill 0.762)
			(layers "*.Cu" "*.Mask")
			(remove_unused_layers no)
			(net "GND")
			(clearance 0.0508)
			(thermal_gap 0.0508)
		)
		(pad "P4" thru_hole circle
			(at 0 7.62)
			(size 1.1684 1.1684)
			(drill 0.762)
			(layers "*.Cu" "*.Mask")
			(remove_unused_layers no)
			(net "GND")
			(clearance 0.0508)
			(thermal_gap 0.0508)
		)
		(pad "P5" thru_hole circle
			(at 0 10.16)
			(size 1.1684 1.1684)
			(drill 0.762)
			(layers "*.Cu" "*.Mask")
			(remove_unused_layers no)
			(net "GND")
			(clearance 0.0508)
			(thermal_gap 0.0508)
		)
		(pad "P6" thru_hole circle
			(at 0 12.7)
			(size 1.1684 1.1684)
			(drill 0.762)
			(layers "*.Cu" "*.Mask")
			(remove_unused_layers no)
			(net "GND")
			(clearance 0.0508)
			(thermal_gap 0.0508)
		)
		(pad "P7" thru_hole circle
			(at 0 15.24)
			(size 1.1684 1.1684)
			(drill 0.762)
			(layers "*.Cu" "*.Mask")
			(remove_unused_layers no)
			(net "GND")
			(clearance 0.0508)
			(thermal_gap 0.0508)
		)
		(pad "P8" thru_hole circle
			(at 0 17.78)
			(size 1.1684 1.1684)
			(drill 0.762)
			(layers "*.Cu" "*.Mask")
			(remove_unused_layers no)
			(net "GND")
			(clearance 0.0508)
			(thermal_gap 0.0508)
		)
		(pad "P9" thru_hole circle
			(at 0 20.32)
			(size 1.1684 1.1684)
			(drill 0.762)
			(layers "*.Cu" "*.Mask")
			(remove_unused_layers no)
			(net "P12V")
			(clearance 0.0508)
			(thermal_gap 0.0508)
		)
		(pad "P10" thru_hole circle
			(at 0 22.86)
			(size 1.1684 1.1684)
			(drill 0.762)
			(layers "*.Cu" "*.Mask")
			(remove_unused_layers no)
			(net "P12V")
			(clearance 0.0508)
			(thermal_gap 0.0508)
		)
		(pad "P11" thru_hole circle
			(at 0 25.4)
			(size 1.1684 1.1684)
			(drill 0.762)
			(layers "*.Cu" "*.Mask")
			(remove_unused_layers no)
			(net "P12V")
			(clearance 0.0508)
			(thermal_gap 0.0508)
		)
		(pad "P12" thru_hole circle
			(at 0 27.94)
			(size 1.1684 1.1684)
			(drill 0.762)
			(layers "*.Cu" "*.Mask")
			(remove_unused_layers no)
			(net "P12V")
			(clearance 0.0508)
			(thermal_gap 0.0508)
		)
		(pad "P13" thru_hole circle
			(at 0 30.48)
			(size 1.1684 1.1684)
			(drill 0.762)
			(layers "*.Cu" "*.Mask")
			(remove_unused_layers no)
			(net "P12V")
			(clearance 0.0508)
			(thermal_gap 0.0508)
		)
		(pad "P14" thru_hole circle
			(at 0 33.02)
			(size 1.1684 1.1684)
			(drill 0.762)
			(layers "*.Cu" "*.Mask")
			(remove_unused_layers no)
			(net "P12V")
			(clearance 0.0508)
			(thermal_gap 0.0508)
		)
		(pad "P15" thru_hole circle
			(at 0 35.56)
			(size 1.1684 1.1684)
			(drill 0.762)
			(layers "*.Cu" "*.Mask")
			(remove_unused_layers no)
			(net "P12V")
			(clearance 0.0508)
			(thermal_gap 0.0508)
		)
		(pad "P16" thru_hole circle
			(at 0 38.1)
			(size 1.1684 1.1684)
			(drill 0.762)
			(layers "*.Cu" "*.Mask")
			(remove_unused_layers no)
			(net "P12V")
			(clearance 0.0508)
			(thermal_gap 0.0508)
		)
		(pad "P17" thru_hole circle
			(at -2.70002 38.1)
			(size 1.1684 1.1684)
			(drill 0.762)
			(layers "*.Cu" "*.Mask")
			(remove_unused_layers no)
			(net "P12V")
			(clearance 0.0508)
			(thermal_gap 0.0508)
		)
		(pad "P18" thru_hole circle
			(at -2.70002 35.56)
			(size 1.1684 1.1684)
			(drill 0.762)
			(layers "*.Cu" "*.Mask")
			(remove_unused_layers no)
			(net "P12V")
			(clearance 0.0508)
			(thermal_gap 0.0508)
		)
		(pad "P19" thru_hole circle
			(at -2.70002 33.02)
			(size 1.1684 1.1684)
			(drill 0.762)
			(layers "*.Cu" "*.Mask")
			(remove_unused_layers no)
			(net "P12V")
			(clearance 0.0508)
			(thermal_gap 0.0508)
		)
		(pad "P20" thru_hole circle
			(at -2.70002 30.48)
			(size 1.1684 1.1684)
			(drill 0.762)
			(layers "*.Cu" "*.Mask")
			(remove_unused_layers no)
			(net "P12V")
			(clearance 0.0508)
			(thermal_gap 0.0508)
		)
		(pad "P21" thru_hole circle
			(at -2.70002 27.94)
			(size 1.1684 1.1684)
			(drill 0.762)
			(layers "*.Cu" "*.Mask")
			(remove_unused_layers no)
			(net "P12V")
			(clearance 0.0508)
			(thermal_gap 0.0508)
		)
		(pad "P22" thru_hole circle
			(at -2.70002 25.4)
			(size 1.1684 1.1684)
			(drill 0.762)
			(layers "*.Cu" "*.Mask")
			(remove_unused_layers no)
			(net "P12V")
			(clearance 0.0508)
			(thermal_gap 0.0508)
		)
		(pad "P23" thru_hole circle
			(at -2.70002 22.86)
			(size 1.1684 1.1684)
			(drill 0.762)
			(layers "*.Cu" "*.Mask")
			(remove_unused_layers no)
			(net "P12V")
			(clearance 0.0508)
			(thermal_gap 0.0508)
		)
		(pad "P24" thru_hole circle
			(at -2.70002 20.32)
			(size 1.1684 1.1684)
			(drill 0.762)
			(layers "*.Cu" "*.Mask")
			(remove_unused_layers no)
			(net "P12V")
			(clearance 0.0508)
			(thermal_gap 0.0508)
		)
		(pad "P25" thru_hole circle
			(at -2.70002 17.78)
			(size 1.1684 1.1684)
			(drill 0.762)
			(layers "*.Cu" "*.Mask")
			(remove_unused_layers no)
			(net "GND")
			(clearance 0.0508)
			(thermal_gap 0.0508)
		)
		(pad "P26" thru_hole circle
			(at -2.70002 15.24)
			(size 1.1684 1.1684)
			(drill 0.762)
			(layers "*.Cu" "*.Mask")
			(remove_unused_layers no)
			(net "GND")
			(clearance 0.0508)
			(thermal_gap 0.0508)
		)
		(pad "P27" thru_hole circle
			(at -2.70002 12.7)
			(size 1.1684 1.1684)
			(drill 0.762)
			(layers "*.Cu" "*.Mask")
			(remove_unused_layers no)
			(net "GND")
			(clearance 0.0508)
			(thermal_gap 0.0508)
		)
		(pad "P28" thru_hole circle
			(at -2.70002 10.16)
			(size 1.1684 1.1684)
			(drill 0.762)
			(layers "*.Cu" "*.Mask")
			(remove_unused_layers no)
			(net "GND")
			(clearance 0.0508)
			(thermal_gap 0.0508)
		)
		(pad "P29" thru_hole circle
			(at -2.70002 7.62)
			(size 1.1684 1.1684)
			(drill 0.762)
			(layers "*.Cu" "*.Mask")
			(remove_unused_layers no)
			(net "GND")
			(clearance 0.0508)
			(thermal_gap 0.0508)
		)
		(pad "P30" thru_hole circle
			(at -2.70002 5.08)
			(size 1.1684 1.1684)
			(drill 0.762)
			(layers "*.Cu" "*.Mask")
			(remove_unused_layers no)
			(net "GND")
			(clearance 0.0508)
			(thermal_gap 0.0508)
		)
		(pad "P31" thru_hole circle
			(at -2.70002 2.54)
			(size 1.1684 1.1684)
			(drill 0.762)
			(layers "*.Cu" "*.Mask")
			(remove_unused_layers no)
			(net "GND")
			(clearance 0.0508)
			(thermal_gap 0.0508)
		)
		(pad "P32" thru_hole circle
			(at -2.70002 0)
			(size 1.1684 1.1684)
			(drill 0.762)
			(layers "*.Cu" "*.Mask")
			(remove_unused_layers no)
			(net "GND")
			(clearance 0.0508)
			(thermal_gap 0.0508)
		)
		(pad "S1" thru_hole circle
			(at 0.55499 41.60012)
			(size 1.1684 1.1684)
			(drill 0.762)
			(layers "*.Cu" "*.Mask")
			(remove_unused_layers no)
			(net "T5_BLAD1_TXD")
			(clearance 0.0508)
			(thermal_gap 0.0508)
		)
		(pad "S2" thru_hole circle
			(at -0.71501 42.87012)
			(size 1.1684 1.1684)
			(drill 0.762)
			(layers "*.Cu" "*.Mask")
			(remove_unused_layers no)
			(net "T5_BLAD1_RXD")
			(clearance 0.0508)
			(thermal_gap 0.0508)
		)
		(pad "S3" thru_hole circle
			(at 0.55499 44.14012)
			(size 1.1684 1.1684)
			(drill 0.762)
			(layers "*.Cu" "*.Mask")
			(remove_unused_layers no)
			(net "T5_BLAD1_EN")
			(clearance 0.0508)
			(thermal_gap 0.0508)
		)
		(pad "S4" thru_hole circle
			(at -0.71501 45.41012)
			(size 1.1684 1.1684)
			(drill 0.762)
			(layers "*.Cu" "*.Mask")
			(remove_unused_layers no)
			(net "B9_PSU_ALERT_N")
			(clearance 0.0508)
			(thermal_gap 0.0508)
		)
		(pad "S5" thru_hole circle
			(at 0.55499 46.68012)
			(size 1.1684 1.1684)
			(drill 0.762)
			(layers "*.Cu" "*.Mask")
			(remove_unused_layers no)
			(net "T5_BLAD2_TXD")
			(clearance 0.0508)
			(thermal_gap 0.0508)
		)
		(pad "S6" thru_hole circle
			(at -0.71501 47.95012)
			(size 1.1684 1.1684)
			(drill 0.762)
			(layers "*.Cu" "*.Mask")
			(remove_unused_layers no)
			(net "T5_BLAD2_RXD")
			(clearance 0.0508)
			(thermal_gap 0.0508)
		)
		(pad "S7" thru_hole circle
			(at -3.25501 47.95012)
			(size 1.1684 1.1684)
			(drill 0.762)
			(layers "*.Cu" "*.Mask")
			(remove_unused_layers no)
			(net "T5_BLAD4_RXD")
			(clearance 0.0508)
			(thermal_gap 0.0508)
		)
		(pad "S8" thru_hole circle
			(at -1.98501 46.68012)
			(size 1.1684 1.1684)
			(drill 0.762)
			(layers "*.Cu" "*.Mask")
			(remove_unused_layers no)
			(net "T5_BLAD4_TXD")
			(clearance 0.0508)
			(thermal_gap 0.0508)
		)
		(pad "S9" thru_hole circle
			(at -3.25501 45.41012)
			(size 1.1684 1.1684)
			(drill 0.762)
			(layers "*.Cu" "*.Mask")
			(remove_unused_layers no)
			(net "B10_PSU_ALERT_N")
			(clearance 0.0508)
			(thermal_gap 0.0508)
		)
		(pad "S10" thru_hole circle
			(at -1.98501 44.14012)
			(size 1.1684 1.1684)
			(drill 0.762)
			(layers "*.Cu" "*.Mask")
			(remove_unused_layers no)
			(net "T5_BLAD3_EN")
			(clearance 0.0508)
			(thermal_gap 0.0508)
		)
		(pad "S11" thru_hole circle
			(at -3.25501 42.87012)
			(size 1.1684 1.1684)
			(drill 0.762)
			(layers "*.Cu" "*.Mask")
			(remove_unused_layers no)
			(net "T5_BLAD3_RXD")
			(clearance 0.0508)
			(thermal_gap 0.0508)
		)
		(pad "S12" thru_hole circle
			(at -1.98501 41.60012)
			(size 1.1684 1.1684)
			(drill 0.762)
			(layers "*.Cu" "*.Mask")
			(remove_unused_layers no)
			(net "T5_BLAD3_TXD")
			(clearance 0.0508)
			(thermal_gap 0.0508)
		)
	)
)
